# S9S_MB_2U (Grand Teton) — schematic netlist excerpt (pin names and nets, part order shuffled) for the footprints in the layout excerpt that follows; sources: Cadence DE-HDL packaged netlist, KiCad conversion of 03242023_DA0F0TMBIJ0_F0T_Motherboard_J_brd_V01_OCP.brd

C2350  Q_CAP_DIFFBUS  DIFF BUS_0.33UF 6.3V 10% X6S  pkg C0402  page 169 : \1\ = USB3_PCH_RX_DN<4> ; \2\ = USB3_PCH_RX_C_DN<4>
C1200  Q_CAP  2.2UF 10V 10% X6S  pkg C0402  page 189 : A = P1V05_PCH_AUX ; B = GND

(kicad_pcb
	(version 20260206)
	(generator "pcbnew")
	(generator_version "10.0")
	(general
		(thickness 1.6)
		(legacy_teardrops no)
	)
	(paper "A4")
	(title_block
		(title "03242023_DA0F0TMBIJ0_F0T_Motherboard_J_brd_V01_OCP.brd")
		(comment 1 "Grand Teton / footprints 5926-5927 of 6105")
	)
	(layers
		(0 "F.Cu" signal "TOP")
		(4 "In1.Cu" signal "GND")
		(6 "In2.Cu" signal "IN1")
		(8 "In3.Cu" signal "GND1")
		(10 "In4.Cu" signal "IN2")
		(12 "In5.Cu" signal "GND2")
		(14 "In6.Cu" signal "IN3")
		(16 "In7.Cu" signal "GND3")
		(18 "In8.Cu" signal "VCC")
		(20 "In9.Cu" signal "VCC1")
		(22 "In10.Cu" signal "GND4")
		(24 "In11.Cu" signal "IN4")
		(26 "In12.Cu" signal "GND5")
		(28 "In13.Cu" signal "IN5")
		(30 "In14.Cu" signal "GND6")
		(32 "In15.Cu" signal "IN6")
		(34 "In16.Cu" signal "GND7")
		(2 "B.Cu" signal "BOTTOM")
		(9 "F.Adhes" user "F.Adhesive")
		(11 "B.Adhes" user "B.Adhesive")
		(13 "F.Paste" user "Package Geometry/Pastemask Top")
		(15 "B.Paste" user "Package Geometry/Pastemask Bottom")
		(5 "F.SilkS" user "Ref Des/Silkscreen Top")
		(7 "B.SilkS" user "Ref Des/Silkscreen Bottom")
		(1 "F.Mask" user "Board Geometry/Soldermask Top")
		(3 "B.Mask" user "Board Geometry/Soldermask Bottom")
		(17 "Dwgs.User" user "User.Drawings")
		(19 "Cmts.User" user "User.Comments")
		(21 "Eco1.User" user "User.Eco1")
		(23 "Eco2.User" user "User.Eco2")
		(25 "Edge.Cuts" user "Board Geometry/Outline")
		(27 "Margin" user)
		(31 "F.CrtYd" user "Package Geometry/Place Bound Top")
		(29 "B.CrtYd" user "Package Geometry/Place Bound Bottom")
		(35 "F.Fab" user "Ref Des/Assembly Top")
		(33 "B.Fab" user "Ref Des/Assembly Bottom")
	)
	(footprint ""
		(layer "B.Cu")
		(at 131.74726 -27.3177)
		(property "Reference" "C2350"
			(at 0 0 0)
			(layer "B.SilkS")
			(hide yes)
			(effects
				(font
					(size 1.27 1.27)
				)
				(justify mirror)
			)
		)
		(property "Value" ""
			(at 0 0 0)
			(layer "B.Fab")
			(effects
				(font
					(size 1.27 1.27)
				)
				(justify mirror)
			)
		)
		(duplicate_pad_numbers_are_jumpers no)
		(fp_line
			(start -0.40005 0.4064)
			(end 0.40005 0.4064)
			(stroke
				(width 0.1524)
				(type default)
			)
			(layer "B.SilkS")
		)
		(fp_line
			(start 0.40005 -0.4064)
			(end -0.40005 -0.4064)
			(stroke
				(width 0.1524)
				(type default)
			)
			(layer "B.SilkS")
		)
		(fp_line
			(start -0.6858 -0.3048)
			(end -0.6858 0.3048)
			(stroke
				(width 0.1)
				(type default)
			)
			(layer "B.Fab")
		)
		(fp_line
			(start -0.6858 0.3048)
			(end -0.1016 0.3048)
			(stroke
				(width 0.1)
				(type default)
			)
			(layer "B.Fab")
		)
		(fp_line
			(start -0.1016 -0.3048)
			(end -0.6858 -0.3048)
			(stroke
				(width 0.1)
				(type default)
			)
			(layer "B.Fab")
		)
		(fp_line
			(start -0.1016 -0.2794)
			(end -0.1016 -0.3048)
			(stroke
				(width 0.1)
				(type default)
			)
			(layer "B.Fab")
		)
		(fp_line
			(start -0.1016 0.2794)
			(end 0.1016 0.2794)
			(stroke
				(width 0.1)
				(type default)
			)
			(layer "B.Fab")
		)
		(fp_line
			(start -0.1016 0.3048)
			(end -0.1016 0.2794)
			(stroke
				(width 0.1)
				(type default)
			)
			(layer "B.Fab")
		)
		(fp_line
			(start 0.1016 -0.3048)
			(end 0.1016 -0.2794)
			(stroke
				(width 0.1)
				(type default)
			)
			(layer "B.Fab")
		)
		(fp_line
			(start 0.1016 -0.2794)
			(end -0.1016 -0.2794)
			(stroke
				(width 0.1)
				(type default)
			)
			(layer "B.Fab")
		)
		(fp_line
			(start 0.1016 0.2794)
			(end 0.1016 0.3048)
			(stroke
				(width 0.1)
				(type default)
			)
			(layer "B.Fab")
		)
		(fp_line
			(start 0.1016 0.3048)
			(end 0.6858 0.3048)
			(stroke
				(width 0.1)
				(type default)
			)
			(layer "B.Fab")
		)
		(fp_line
			(start 0.6858 -0.3048)
			(end 0.1016 -0.3048)
			(stroke
				(width 0.1)
				(type default)
			)
			(layer "B.Fab")
		)
		(fp_line
			(start 0.6858 0.3048)
			(end 0.6858 -0.3048)
			(stroke
				(width 0.1)
				(type default)
			)
			(layer "B.Fab")
		)
		(pad "1" smd rect
			(at 0.40005 0)
			(size 0.4572 0.508)
			(layers "B.Cu" "B.Mask" "B.Paste")
			(net "USB3_PCH_RX_DN<4>")
		)
		(pad "2" smd rect
			(at -0.40005 0)
			(size 0.4572 0.508)
			(layers "B.Cu" "B.Mask" "B.Paste")
			(net "USB3_PCH_RX_C_DN<4>")
		)
		(zone
			(layer "In16.Cu")
			(hatch none 0.5)
			(connect_pads
				(clearance 0)
			)
			(min_thickness 0.25)
			(keepout
				(tracks not_allowed)
				(vias allowed)
				(pads allowed)
				(copperpour not_allowed)
				(footprints allowed)
			)
			(placement
				(enabled no)
				(sheetname "")
			)
			(fill
				(thermal_gap 0.5)
				(thermal_bridge_width 0.5)
				(island_removal_mode 0)
			)
			(polygon
				(pts
					(xy 131.62661 -27.0129) (xy 131.06781 -27.0129) (xy 131.06781 -27.6225) (xy 131.62661 -27.6225)
				)
			)
		)
		(zone
			(layer "In16.Cu")
			(hatch none 0.5)
			(connect_pads
				(clearance 0)
			)
			(min_thickness 0.25)
			(keepout
				(tracks not_allowed)
				(vias allowed)
				(pads allowed)
				(copperpour not_allowed)
				(footprints allowed)
			)
			(placement
				(enabled no)
				(sheetname "")
			)
			(fill
				(thermal_gap 0.5)
				(thermal_bridge_width 0.5)
				(island_removal_mode 0)
			)
			(polygon
				(pts
					(xy 132.42671 -27.0129) (xy 131.86791 -27.0129) (xy 131.86791 -27.6225) (xy 132.42671 -27.6225)
				)
			)
		)
	)
	(footprint ""
		(layer "B.Cu")
		(at 339.267038 -48.516286 180)
		(property "Reference" "C1200"
			(at 0 0 0)
			(layer "B.SilkS")
			(hide yes)
			(effects
				(font
					(size 1.27 1.27)
				)
				(justify mirror)
			)
		)
		(property "Value" ""
			(at 0 0 0)
			(layer "B.Fab")
			(effects
				(font
					(size 1.27 1.27)
				)
				(justify mirror)
			)
		)
		(duplicate_pad_numbers_are_jumpers no)
		(fp_line
			(start 0.7874 0.4064)
			(end 0.7874 -0.4064)
			(stroke
				(width 0.1524)
				(type default)
			)
			(layer "B.SilkS")
		)
		(fp_line
			(start 0.7874 -0.4064)
			(end -0.7874 -0.4064)
			(stroke
				(width 0.1524)
				(type default)
			)
			(layer "B.SilkS")
		)
		(fp_line
			(start -0.7874 0.4064)
			(end 0.7874 0.4064)
			(stroke
				(width 0.1524)
				(type default)
			)
			(layer "B.SilkS")
		)
		(fp_line
			(start -0.7874 -0.4064)
			(end -0.7874 0.4064)
			(stroke
				(width 0.1524)
				(type default)
			)
			(layer "B.SilkS")
		)
		(fp_line
			(start 0.67945 0.3048)
			(end 0.67945 -0.305054)
			(stroke
				(width 0.1)
				(type default)
			)
			(layer "B.Fab")
		)
		(fp_line
			(start 0.67945 -0.305054)
			(end 0.12065 -0.305054)
			(stroke
				(width 0.1)
				(type default)
			)
			(layer "B.Fab")
		)
		(fp_line
			(start 0.12065 0.3048)
			(end 0.67945 0.3048)
			(stroke
				(width 0.1)
				(type default)
			)
			(layer "B.Fab")
		)
		(fp_line
			(start 0.12065 0.2794)
			(end 0.12065 0.3048)
			(stroke
				(width 0.1)
				(type default)
			)
			(layer "B.Fab")
		)
		(fp_line
			(start 0.12065 -0.2794)
			(end -0.12065 -0.2794)
			(stroke
				(width 0.1)
				(type default)
			)
			(layer "B.Fab")
		)
		(fp_line
			(start 0.12065 -0.305054)
			(end 0.12065 -0.2794)
			(stroke
				(width 0.1)
				(type default)
			)
			(layer "B.Fab")
		)
		(fp_line
			(start -0.120396 0.3048)
			(end -0.120396 0.2794)
			(stroke
				(width 0.1)
				(type default)
			)
			(layer "B.Fab")
		)
		(fp_line
			(start -0.120396 0.2794)
			(end 0.12065 0.2794)
			(stroke
				(width 0.1)
				(type default)
			)
			(layer "B.Fab")
		)
		(fp_line
			(start -0.12065 -0.2794)
			(end -0.12065 -0.3048)
			(stroke
				(width 0.1)
				(type default)
			)
			(layer "B.Fab")
		)
		(fp_line
			(start -0.12065 -0.3048)
			(end -0.67945 -0.3048)
			(stroke
				(width 0.1)
				(type default)
			)
			(layer "B.Fab")
		)
		(fp_line
			(start -0.67945 0.3048)
			(end -0.120396 0.3048)
			(stroke
				(width 0.1)
				(type default)
			)
			(layer "B.Fab")
		)
		(fp_line
			(start -0.67945 -0.3048)
			(end -0.67945 0.3048)
			(stroke
				(width 0.1)
				(type default)
			)
			(layer "B.Fab")
		)
		(pad "1" smd circle
			(at 0.40005 0)
			(size 0 0)
			(layers "B.Cu" "B.Mask" "B.Paste")
			(net "P1V05_PCH_AUX")
		)
		(pad "2" smd circle
			(at -0.40005 0)
			(size 0 0)
			(layers "B.Cu" "B.Mask" "B.Paste")
			(net "GND")
		)
	)
)
